FILE_TYPE=LIBRARY_PARTS ;
PRIMITIVE 'VERT_BATT_3PIN','VERT_BATT_3PIN_TH','VERT_BATT_3PIN_PIP';
 PIN
  'N':
    PIN_NUMBER='(3)';
    PIN_TYPE='ANALOG';
    NO_LOAD_CHECK='BOTH';
    NO_IO_CHECK='BOTH';
    ALLOW_CONNECT='TRUE';
  'P1':
    PIN_NUMBER='(1)';
    PIN_TYPE='ANALOG';
    NO_LOAD_CHECK='BOTH';
    NO_IO_CHECK='BOTH';
    ALLOW_CONNECT='TRUE';
  'P2':
    PIN_NUMBER='(2)';
    PIN_TYPE='ANALOG';
    NO_LOAD_CHECK='BOTH';
    NO_IO_CHECK='BOTH';
    ALLOW_CONNECT='TRUE';
 END_PIN;
 BODY
  PART_NAME='VERT_BATT_3PIN';
  PHYS_DES_PREFIX='BT';
 END_BODY;
END_PRIMITIVE;
END.
